(kicad_pcb
	(version 20260206)
	(generator "pcbnew")
	(generator_version "10.0")
	(general
		(thickness 1.6)
		(legacy_teardrops no)
	)
	(paper "A4")
	(title_block
		(title "03242023_DA0F0TMBIJ0_F0T_Motherboard_J_brd_V01_OCP.brd")
		(comment 1 "Grand Teton / footprints 2480-2485 of 6105")
	)
	(layers
		(0 "F.Cu" signal "TOP")
		(4 "In1.Cu" signal "GND")
		(6 "In2.Cu" signal "IN1")
		(8 "In3.Cu" signal "GND1")
		(10 "In4.Cu" signal "IN2")
		(12 "In5.Cu" signal "GND2")
		(14 "In6.Cu" signal "IN3")
		(16 "In7.Cu" signal "GND3")
		(18 "In8.Cu" signal "VCC")
		(20 "In9.Cu" signal "VCC1")
		(22 "In10.Cu" signal "GND4")
		(24 "In11.Cu" signal "IN4")
		(26 "In12.Cu" signal "GND5")
		(28 "In13.Cu" signal "IN5")
		(30 "In14.Cu" signal "GND6")
		(32 "In15.Cu" signal "IN6")
		(34 "In16.Cu" signal "GND7")
		(2 "B.Cu" signal "BOTTOM")
		(9 "F.Adhes" user "F.Adhesive")
		(11 "B.Adhes" user "B.Adhesive")
		(13 "F.Paste" user "Package Geometry/Pastemask Top")
		(15 "B.Paste" user "Package Geometry/Pastemask Bottom")
		(5 "F.SilkS" user "Ref Des/Silkscreen Top")
		(7 "B.SilkS" user "Ref Des/Silkscreen Bottom")
		(1 "F.Mask" user "Board Geometry/Soldermask Top")
		(3 "B.Mask" user "Board Geometry/Soldermask Bottom")
		(17 "Dwgs.User" user "User.Drawings")
		(19 "Cmts.User" user "User.Comments")
		(21 "Eco1.User" user "User.Eco1")
		(23 "Eco2.User" user "User.Eco2")
		(25 "Edge.Cuts" user "Board Geometry/Outline")
		(27 "Margin" user)
		(31 "F.CrtYd" user "Package Geometry/Place Bound Top")
		(29 "B.CrtYd" user "Package Geometry/Place Bound Bottom")
		(35 "F.Fab" user "Ref Des/Assembly Top")
		(33 "B.Fab" user "Ref Des/Assembly Bottom")
	)
	(footprint ""
		(layer "F.Cu")
		(at 228.816662 -122.151902 180)
		(property "Reference" "R1274"
			(at 0 0 180)
			(layer "F.SilkS")
			(hide yes)
			(effects
				(font
					(size 1.27 1.27)
				)
			)
		)
		(property "Value" ""
			(at 0 0 180)
			(layer "F.Fab")
			(effects
				(font
					(size 1.27 1.27)
				)
			)
		)
		(duplicate_pad_numbers_are_jumpers no)
		(fp_line
			(start 0.7874 -0.4064)
			(end 0.7874 0.164338)
			(stroke
				(width 0.1524)
				(type default)
			)
			(layer "F.SilkS")
		)
		(fp_line
			(start 0.610362 0.4064)
			(end -0.507238 0.4064)
			(stroke
				(width 0.1524)
				(type default)
			)
			(layer "F.SilkS")
		)
		(fp_line
			(start -0.7874 0.067818)
			(end -0.7874 -0.4064)
			(stroke
				(width 0.1524)
				(type default)
			)
			(layer "F.SilkS")
		)
		(fp_line
			(start -0.7874 -0.4064)
			(end 0.7874 -0.4064)
			(stroke
				(width 0.1524)
				(type default)
			)
			(layer "F.SilkS")
		)
		(fp_line
			(start 0.67945 0.3048)
			(end 0.120396 0.3048)
			(stroke
				(width 0.1)
				(type default)
			)
			(layer "F.Fab")
		)
		(fp_line
			(start 0.67945 -0.3048)
			(end 0.67945 0.3048)
			(stroke
				(width 0.1)
				(type default)
			)
			(layer "F.Fab")
		)
		(fp_line
			(start 0.12065 -0.2794)
			(end 0.12065 -0.3048)
			(stroke
				(width 0.1)
				(type default)
			)
			(layer "F.Fab")
		)
		(fp_line
			(start 0.12065 -0.3048)
			(end 0.67945 -0.3048)
			(stroke
				(width 0.1)
				(type default)
			)
			(layer "F.Fab")
		)
		(fp_line
			(start 0.120396 0.3048)
			(end 0.120396 0.2794)
			(stroke
				(width 0.1)
				(type default)
			)
			(layer "F.Fab")
		)
		(fp_line
			(start 0.120396 0.2794)
			(end -0.12065 0.2794)
			(stroke
				(width 0.1)
				(type default)
			)
			(layer "F.Fab")
		)
		(fp_line
			(start -0.12065 0.3048)
			(end -0.67945 0.3048)
			(stroke
				(width 0.1)
				(type default)
			)
			(layer "F.Fab")
		)
		(fp_line
			(start -0.12065 0.2794)
			(end -0.12065 0.3048)
			(stroke
				(width 0.1)
				(type default)
			)
			(layer "F.Fab")
		)
		(fp_line
			(start -0.12065 -0.2794)
			(end 0.12065 -0.2794)
			(stroke
				(width 0.1)
				(type default)
			)
			(layer "F.Fab")
		)
		(fp_line
			(start -0.12065 -0.305054)
			(end -0.12065 -0.2794)
			(stroke
				(width 0.1)
				(type default)
			)
			(layer "F.Fab")
		)
		(fp_line
			(start -0.67945 0.3048)
			(end -0.67945 -0.305054)
			(stroke
				(width 0.1)
				(type default)
			)
			(layer "F.Fab")
		)
		(fp_line
			(start -0.67945 -0.305054)
			(end -0.12065 -0.305054)
			(stroke
				(width 0.1)
				(type default)
			)
			(layer "F.Fab")
		)
		(pad "1" smd circle
			(at -0.40005 0 180)
			(size 0 0)
			(layers "F.Cu" "F.Mask" "F.Paste")
			(net "CLK_100M_OCP_SFF_2_R_DN")
		)
		(pad "2" smd circle
			(at 0.40005 0 180)
			(size 0 0)
			(layers "F.Cu" "F.Mask" "F.Paste")
			(net "CLK_100M_OCP_SFF_2_DN")
		)
	)
	(footprint ""
		(layer "F.Cu")
		(at 93.597476 -79.078836)
		(property "Reference" "D96"
			(at -47.22241 38.649402 90)
			(unlocked yes)
			(layer "F.SilkS")
			(effects
				(font
					(size 0.635 0.4064)
					(thickness 0.1524)
				)
				(justify left)
			)
		)
		(property "Value" ""
			(at 0 0 0)
			(layer "F.Fab")
			(effects
				(font
					(size 1.27 1.27)
				)
			)
		)
		(duplicate_pad_numbers_are_jumpers no)
		(fp_line
			(start -0.90678 0.4826)
			(end -0.90678 -0.4699)
			(stroke
				(width 0.1524)
				(type default)
			)
			(layer "F.SilkS")
		)
		(fp_line
			(start -0.89408 -0.4826)
			(end 0.90678 -0.4826)
			(stroke
				(width 0.1524)
				(type default)
			)
			(layer "F.SilkS")
		)
		(fp_line
			(start -0.79248 -0.4826)
			(end 1.03378 -0.4826)
			(stroke
				(width 0.1524)
				(type default)
			)
			(layer "F.SilkS")
		)
		(fp_line
			(start -0.64008 -0.4826)
			(end 1.16078 -0.4826)
			(stroke
				(width 0.1524)
				(type default)
			)
			(layer "F.SilkS")
		)
		(fp_line
			(start 0.90678 -0.4826)
			(end 0.90678 0.4826)
			(stroke
				(width 0.1524)
				(type default)
			)
			(layer "F.SilkS")
		)
		(fp_line
			(start 0.90678 0.4826)
			(end -0.90678 0.4826)
			(stroke
				(width 0.1524)
				(type default)
			)
			(layer "F.SilkS")
		)
		(fp_line
			(start 1.03378 -0.4826)
			(end 1.03378 0.4826)
			(stroke
				(width 0.1524)
				(type default)
			)
			(layer "F.SilkS")
		)
		(fp_line
			(start 1.03378 0.4826)
			(end -0.79248 0.4826)
			(stroke
				(width 0.1524)
				(type default)
			)
			(layer "F.SilkS")
		)
		(fp_line
			(start 1.16078 -0.4826)
			(end 1.16078 0.4826)
			(stroke
				(width 0.1524)
				(type default)
			)
			(layer "F.SilkS")
		)
		(fp_line
			(start 1.16078 0.4826)
			(end -0.64008 0.4826)
			(stroke
				(width 0.1524)
				(type default)
			)
			(layer "F.SilkS")
		)
		(fp_line
			(start -0.499872 -0.249936)
			(end 0.499872 -0.249936)
			(stroke
				(width 0.1)
				(type default)
			)
			(layer "F.Fab")
		)
		(fp_line
			(start -0.499872 0.249936)
			(end -0.499872 -0.249936)
			(stroke
				(width 0.1)
				(type default)
			)
			(layer "F.Fab")
		)
		(fp_line
			(start 0.499872 -0.249936)
			(end 0.499872 0.249936)
			(stroke
				(width 0.1)
				(type default)
			)
			(layer "F.Fab")
		)
		(fp_line
			(start 0.499872 0.249936)
			(end -0.499872 0.249936)
			(stroke
				(width 0.1)
				(type default)
			)
			(layer "F.Fab")
		)
		(pad "A" smd rect
			(at -0.47498 0)
			(size 0.6096 0.7112)
			(layers "F.Cu" "F.Mask" "F.Paste")
			(net "LED_PWRGD_PS_PWROK_PLD")
		)
		(pad "C" smd rect
			(at 0.47498 0)
			(size 0.6096 0.7112)
			(layers "F.Cu" "F.Mask" "F.Paste")
			(net "LED_PWRGD_PS_PWROK_PLD_D")
		)
	)
	(footprint ""
		(layer "F.Cu")
		(at 74.615802 -74.901552 -90)
		(property "Reference" "R3096"
			(at 0 0 270)
			(layer "F.SilkS")
			(hide yes)
			(effects
				(font
					(size 1.27 1.27)
				)
			)
		)
		(property "Value" ""
			(at 0 0 270)
			(layer "F.Fab")
			(effects
				(font
					(size 1.27 1.27)
				)
			)
		)
		(duplicate_pad_numbers_are_jumpers no)
		(fp_line
			(start -0.7874 0.4064)
			(end -0.7874 -0.4064)
			(stroke
				(width 0.1524)
				(type default)
			)
			(layer "F.SilkS")
		)
		(fp_line
			(start 0.7874 0.4064)
			(end -0.7874 0.4064)
			(stroke
				(width 0.1524)
				(type default)
			)
			(layer "F.SilkS")
		)
		(fp_line
			(start -0.7874 -0.4064)
			(end 0.7874 -0.4064)
			(stroke
				(width 0.1524)
				(type default)
			)
			(layer "F.SilkS")
		)
		(fp_line
			(start 0.7874 -0.4064)
			(end 0.7874 0.4064)
			(stroke
				(width 0.1524)
				(type default)
			)
			(layer "F.SilkS")
		)
		(fp_line
			(start -0.67945 0.3048)
			(end -0.67945 -0.305054)
			(stroke
				(width 0.1)
				(type default)
			)
			(layer "F.Fab")
		)
		(fp_line
			(start -0.12065 0.3048)
			(end -0.67945 0.3048)
			(stroke
				(width 0.1)
				(type default)
			)
			(layer "F.Fab")
		)
		(fp_line
			(start 0.120396 0.3048)
			(end 0.120396 0.2794)
			(stroke
				(width 0.1)
				(type default)
			)
			(layer "F.Fab")
		)
		(fp_line
			(start 0.67945 0.3048)
			(end 0.120396 0.3048)
			(stroke
				(width 0.1)
				(type default)
			)
			(layer "F.Fab")
		)
		(fp_line
			(start -0.12065 0.2794)
			(end -0.12065 0.3048)
			(stroke
				(width 0.1)
				(type default)
			)
			(layer "F.Fab")
		)
		(fp_line
			(start 0.120396 0.2794)
			(end -0.12065 0.2794)
			(stroke
				(width 0.1)
				(type default)
			)
			(layer "F.Fab")
		)
		(fp_line
			(start -0.12065 -0.2794)
			(end 0.12065 -0.2794)
			(stroke
				(width 0.1)
				(type default)
			)
			(layer "F.Fab")
		)
		(fp_line
			(start 0.12065 -0.2794)
			(end 0.12065 -0.3048)
			(stroke
				(width 0.1)
				(type default)
			)
			(layer "F.Fab")
		)
		(fp_line
			(start 0.12065 -0.3048)
			(end 0.67945 -0.3048)
			(stroke
				(width 0.1)
				(type default)
			)
			(layer "F.Fab")
		)
		(fp_line
			(start 0.67945 -0.3048)
			(end 0.67945 0.3048)
			(stroke
				(width 0.1)
				(type default)
			)
			(layer "F.Fab")
		)
		(fp_line
			(start -0.67945 -0.305054)
			(end -0.12065 -0.305054)
			(stroke
				(width 0.1)
				(type default)
			)
			(layer "F.Fab")
		)
		(fp_line
			(start -0.12065 -0.305054)
			(end -0.12065 -0.2794)
			(stroke
				(width 0.1)
				(type default)
			)
			(layer "F.Fab")
		)
		(pad "1" smd circle
			(at -0.40005 0 270)
			(size 0 0)
			(layers "F.Cu" "F.Mask" "F.Paste")
			(net "LED_PWRGD_PVCCFA_EHV_CPU1")
		)
		(pad "2" smd circle
			(at 0.40005 0 270)
			(size 0 0)
			(layers "F.Cu" "F.Mask" "F.Paste")
			(net "P3V3_AUX")
		)
	)
	(footprint ""
		(layer "F.Cu")
		(at 205.397608 -399.743422 180)
		(property "Reference" "PC2348"
			(at 0 0 180)
			(layer "F.SilkS")
			(hide yes)
			(effects
				(font
					(size 1.27 1.27)
				)
			)
		)
		(property "Value" ""
			(at 0 0 180)
			(layer "F.Fab")
			(effects
				(font
					(size 1.27 1.27)
				)
			)
		)
		(duplicate_pad_numbers_are_jumpers no)
		(fp_line
			(start 0.7874 0.4064)
			(end -0.7874 0.4064)
			(stroke
				(width 0.1524)
				(type default)
			)
			(layer "F.SilkS")
		)
		(fp_line
			(start 0.7874 -0.4064)
			(end 0.7874 0.4064)
			(stroke
				(width 0.1524)
				(type default)
			)
			(layer "F.SilkS")
		)
		(fp_line
			(start -0.7874 0.4064)
			(end -0.7874 -0.4064)
			(stroke
				(width 0.1524)
				(type default)
			)
			(layer "F.SilkS")
		)
		(fp_line
			(start -0.7874 -0.4064)
			(end 0.7874 -0.4064)
			(stroke
				(width 0.1524)
				(type default)
			)
			(layer "F.SilkS")
		)
		(fp_line
			(start 0.67945 0.3048)
			(end 0.120396 0.3048)
			(stroke
				(width 0.1)
				(type default)
			)
			(layer "F.Fab")
		)
		(fp_line
			(start 0.67945 -0.3048)
			(end 0.67945 0.3048)
			(stroke
				(width 0.1)
				(type default)
			)
			(layer "F.Fab")
		)
		(fp_line
			(start 0.12065 -0.2794)
			(end 0.12065 -0.3048)
			(stroke
				(width 0.1)
				(type default)
			)
			(layer "F.Fab")
		)
		(fp_line
			(start 0.12065 -0.3048)
			(end 0.67945 -0.3048)
			(stroke
				(width 0.1)
				(type default)
			)
			(layer "F.Fab")
		)
		(fp_line
			(start 0.120396 0.3048)
			(end 0.120396 0.2794)
			(stroke
				(width 0.1)
				(type default)
			)
			(layer "F.Fab")
		)
		(fp_line
			(start 0.120396 0.2794)
			(end -0.12065 0.2794)
			(stroke
				(width 0.1)
				(type default)
			)
			(layer "F.Fab")
		)
		(fp_line
			(start -0.12065 0.3048)
			(end -0.67945 0.3048)
			(stroke
				(width 0.1)
				(type default)
			)
			(layer "F.Fab")
		)
		(fp_line
			(start -0.12065 0.2794)
			(end -0.12065 0.3048)
			(stroke
				(width 0.1)
				(type default)
			)
			(layer "F.Fab")
		)
		(fp_line
			(start -0.12065 -0.2794)
			(end 0.12065 -0.2794)
			(stroke
				(width 0.1)
				(type default)
			)
			(layer "F.Fab")
		)
		(fp_line
			(start -0.12065 -0.305054)
			(end -0.12065 -0.2794)
			(stroke
				(width 0.1)
				(type default)
			)
			(layer "F.Fab")
		)
		(fp_line
			(start -0.67945 0.3048)
			(end -0.67945 -0.305054)
			(stroke
				(width 0.1)
				(type default)
			)
			(layer "F.Fab")
		)
		(fp_line
			(start -0.67945 -0.305054)
			(end -0.12065 -0.305054)
			(stroke
				(width 0.1)
				(type default)
			)
			(layer "F.Fab")
		)
		(pad "1" smd circle
			(at -0.40005 0 180)
			(size 0 0)
			(layers "F.Cu" "F.Mask" "F.Paste")
			(net "HSC_OCREF")
		)
		(pad "2" smd circle
			(at 0.40005 0 180)
			(size 0 0)
			(layers "F.Cu" "F.Mask" "F.Paste")
			(net "AGND_HSC")
		)
	)
	(footprint ""
		(layer "F.Cu")
		(at 319.8241 -76.585064 -90)
		(property "Reference" "R2234"
			(at 0 0 270)
			(layer "F.SilkS")
			(hide yes)
			(effects
				(font
					(size 1.27 1.27)
				)
			)
		)
		(property "Value" ""
			(at 0 0 270)
			(layer "F.Fab")
			(effects
				(font
					(size 1.27 1.27)
				)
			)
		)
		(duplicate_pad_numbers_are_jumpers no)
		(fp_line
			(start -0.7874 0.4064)
			(end -0.7874 -0.4064)
			(stroke
				(width 0.1524)
				(type default)
			)
			(layer "F.SilkS")
		)
		(fp_line
			(start 0.7874 0.4064)
			(end -0.7874 0.4064)
			(stroke
				(width 0.1524)
				(type default)
			)
			(layer "F.SilkS")
		)
		(fp_line
			(start -0.7874 -0.4064)
			(end 0.7874 -0.4064)
			(stroke
				(width 0.1524)
				(type default)
			)
			(layer "F.SilkS")
		)
		(fp_line
			(start 0.7874 -0.4064)
			(end 0.7874 0.4064)
			(stroke
				(width 0.1524)
				(type default)
			)
			(layer "F.SilkS")
		)
		(fp_line
			(start -0.67945 0.3048)
			(end -0.67945 -0.305054)
			(stroke
				(width 0.1)
				(type default)
			)
			(layer "F.Fab")
		)
		(fp_line
			(start -0.12065 0.3048)
			(end -0.67945 0.3048)
			(stroke
				(width 0.1)
				(type default)
			)
			(layer "F.Fab")
		)
		(fp_line
			(start 0.120396 0.3048)
			(end 0.120396 0.2794)
			(stroke
				(width 0.1)
				(type default)
			)
			(layer "F.Fab")
		)
		(fp_line
			(start 0.67945 0.3048)
			(end 0.120396 0.3048)
			(stroke
				(width 0.1)
				(type default)
			)
			(layer "F.Fab")
		)
		(fp_line
			(start -0.12065 0.2794)
			(end -0.12065 0.3048)
			(stroke
				(width 0.1)
				(type default)
			)
			(layer "F.Fab")
		)
		(fp_line
			(start 0.120396 0.2794)
			(end -0.12065 0.2794)
			(stroke
				(width 0.1)
				(type default)
			)
			(layer "F.Fab")
		)
		(fp_line
			(start -0.12065 -0.2794)
			(end 0.12065 -0.2794)
			(stroke
				(width 0.1)
				(type default)
			)
			(layer "F.Fab")
		)
		(fp_line
			(start 0.12065 -0.2794)
			(end 0.12065 -0.3048)
			(stroke
				(width 0.1)
				(type default)
			)
			(layer "F.Fab")
		)
		(fp_line
			(start 0.12065 -0.3048)
			(end 0.67945 -0.3048)
			(stroke
				(width 0.1)
				(type default)
			)
			(layer "F.Fab")
		)
		(fp_line
			(start 0.67945 -0.3048)
			(end 0.67945 0.3048)
			(stroke
				(width 0.1)
				(type default)
			)
			(layer "F.Fab")
		)
		(fp_line
			(start -0.67945 -0.305054)
			(end -0.12065 -0.305054)
			(stroke
				(width 0.1)
				(type default)
			)
			(layer "F.Fab")
		)
		(fp_line
			(start -0.12065 -0.305054)
			(end -0.12065 -0.2794)
			(stroke
				(width 0.1)
				(type default)
			)
			(layer "F.Fab")
		)
		(pad "1" smd circle
			(at -0.40005 0 270)
			(size 0 0)
			(layers "F.Cu" "F.Mask" "F.Paste")
			(net "P1V05_PCH_AUX")
		)
		(pad "2" smd circle
			(at 0.40005 0 270)
			(size 0 0)
			(layers "F.Cu" "F.Mask" "F.Paste")
			(net "FM_BOARD_SKU_ID4")
		)
	)
	(footprint ""
		(layer "F.Cu")
		(at 24.050752 -401.790408)
		(property "Reference" "R3321"
			(at 0 0 0)
			(layer "F.SilkS")
			(hide yes)
			(effects
				(font
					(size 1.27 1.27)
				)
			)
		)
		(property "Value" ""
			(at 0 0 0)
			(layer "F.Fab")
			(effects
				(font
					(size 1.27 1.27)
				)
			)
		)
		(duplicate_pad_numbers_are_jumpers no)
		(fp_line
			(start -0.7874 -0.4064)
			(end 0.7874 -0.4064)
			(stroke
				(width 0.1524)
				(type default)
			)
			(layer "F.SilkS")
		)
		(fp_line
			(start -0.7874 0.4064)
			(end -0.7874 -0.4064)
			(stroke
				(width 0.1524)
				(type default)
			)
			(layer "F.SilkS")
		)
		(fp_line
			(start 0.7874 -0.4064)
			(end 0.7874 0.4064)
			(stroke
				(width 0.1524)
				(type default)
			)
			(layer "F.SilkS")
		)
		(fp_line
			(start 0.7874 0.4064)
			(end -0.7874 0.4064)
			(stroke
				(width 0.1524)
				(type default)
			)
			(layer "F.SilkS")
		)
		(fp_line
			(start -0.67945 -0.305054)
			(end -0.12065 -0.305054)
			(stroke
				(width 0.1)
				(type default)
			)
			(layer "F.Fab")
		)
		(fp_line
			(start -0.67945 0.3048)
			(end -0.67945 -0.305054)
			(stroke
				(width 0.1)
				(type default)
			)
			(layer "F.Fab")
		)
		(fp_line
			(start -0.12065 -0.305054)
			(end -0.12065 -0.2794)
			(stroke
				(width 0.1)
				(type default)
			)
			(layer "F.Fab")
		)
		(fp_line
			(start -0.12065 -0.2794)
			(end 0.12065 -0.2794)
			(stroke
				(width 0.1)
				(type default)
			)
			(layer "F.Fab")
		)
		(fp_line
			(start -0.12065 0.2794)
			(end -0.12065 0.3048)
			(stroke
				(width 0.1)
				(type default)
			)
			(layer "F.Fab")
		)
		(fp_line
			(start -0.12065 0.3048)
			(end -0.67945 0.3048)
			(stroke
				(width 0.1)
				(type default)
			)
			(layer "F.Fab")
		)
		(fp_line
			(start 0.120396 0.2794)
			(end -0.12065 0.2794)
			(stroke
				(width 0.1)
				(type default)
			)
			(layer "F.Fab")
		)
		(fp_line
			(start 0.120396 0.3048)
			(end 0.120396 0.2794)
			(stroke
				(width 0.1)
				(type default)
			)
			(layer "F.Fab")
		)
		(fp_line
			(start 0.12065 -0.3048)
			(end 0.67945 -0.3048)
			(stroke
				(width 0.1)
				(type default)
			)
			(layer "F.Fab")
		)
		(fp_line
			(start 0.12065 -0.2794)
			(end 0.12065 -0.3048)
			(stroke
				(width 0.1)
				(type default)
			)
			(layer "F.Fab")
		)
		(fp_line
			(start 0.67945 -0.3048)
			(end 0.67945 0.3048)
			(stroke
				(width 0.1)
				(type default)
			)
			(layer "F.Fab")
		)
		(fp_line
			(start 0.67945 0.3048)
			(end 0.120396 0.3048)
			(stroke
				(width 0.1)
				(type default)
			)
			(layer "F.Fab")
		)
		(pad "1" smd circle
			(at -0.40005 0)
			(size 0 0)
			(layers "F.Cu" "F.Mask" "F.Paste")
			(net "P3V3_AUX")
		)
		(pad "2" smd circle
			(at 0.40005 0)
			(size 0 0)
			(layers "F.Cu" "F.Mask" "F.Paste")
			(net "GPU_FPGA_READY_ISO")
		)
	)
)
